(kicad_pcb
	(version 20260206)
	(generator "pcbnew")
	(generator_version "10.0")
	(general
		(thickness 1.6)
		(legacy_teardrops no)
	)
	(paper "A4")
	(title_block
		(title "12092022_DA0F0TFB6D0_F0T_FAN_BOARD_MP5048_D_brd_v02_OCP.brd")
		(comment 1 "Grand Teton / footprints 609-613 of 924")
	)
	(layers
		(0 "F.Cu" signal "TOP")
		(4 "In1.Cu" signal "GND")
		(6 "In2.Cu" signal "IN1")
		(8 "In3.Cu" signal "IN2")
		(10 "In4.Cu" signal "GND1")
		(2 "B.Cu" signal "BOTTOM")
		(9 "F.Adhes" user "F.Adhesive")
		(11 "B.Adhes" user "B.Adhesive")
		(13 "F.Paste" user "Package Geometry/Pastemask Top")
		(15 "B.Paste" user "Package Geometry/Pastemask Bottom")
		(5 "F.SilkS" user "Ref Des/Silkscreen Top")
		(7 "B.SilkS" user "Ref Des/Silkscreen Bottom")
		(1 "F.Mask" user "Board Geometry/Soldermask Top")
		(3 "B.Mask" user "Board Geometry/Soldermask Bottom")
		(17 "Dwgs.User" user "User.Drawings")
		(19 "Cmts.User" user "User.Comments")
		(21 "Eco1.User" user "User.Eco1")
		(23 "Eco2.User" user "User.Eco2")
		(25 "Edge.Cuts" user "Board Geometry/Outline")
		(27 "Margin" user)
		(31 "F.CrtYd" user "Package Geometry/Place Bound Top")
		(29 "B.CrtYd" user "Package Geometry/Place Bound Bottom")
		(35 "F.Fab" user "Ref Des/Assembly Top")
		(33 "B.Fab" user "Ref Des/Assembly Bottom")
	)
	(footprint ""
		(layer "F.Cu")
		(at 34.925 -275.608288 180)
		(property "Reference" "PC7"
			(at -3.175 -6.013958 0)
			(unlocked yes)
			(layer "F.SilkS")
			(effects
				(font
					(size 0.7874 0.5842)
					(thickness 0.1524)
				)
				(justify left)
			)
		)
		(property "Value" ""
			(at 0 0 180)
			(layer "F.Fab")
			(effects
				(font
					(size 1.27 1.27)
				)
			)
		)
		(duplicate_pad_numbers_are_jumpers no)
		(fp_line
			(start 5.249926 5.249926)
			(end 5.249926 1.2446)
			(stroke
				(width 0.1524)
				(type default)
			)
			(layer "F.SilkS")
		)
		(fp_line
			(start 5.249926 -1.2446)
			(end 5.249926 -5.249926)
			(stroke
				(width 0.1524)
				(type default)
			)
			(layer "F.SilkS")
		)
		(fp_line
			(start 5.249926 -5.249926)
			(end -3.979926 -5.249926)
			(stroke
				(width 0.1524)
				(type default)
			)
			(layer "F.SilkS")
		)
		(fp_line
			(start -3.979926 5.249926)
			(end 5.249926 5.249926)
			(stroke
				(width 0.1524)
				(type default)
			)
			(layer "F.SilkS")
		)
		(fp_line
			(start -3.979926 -5.249926)
			(end -5.249926 -3.979926)
			(stroke
				(width 0.1524)
				(type default)
			)
			(layer "F.SilkS")
		)
		(fp_line
			(start -5.249926 3.979926)
			(end -3.979926 5.249926)
			(stroke
				(width 0.1524)
				(type default)
			)
			(layer "F.SilkS")
		)
		(fp_line
			(start -5.249926 1.2446)
			(end -5.249926 3.979926)
			(stroke
				(width 0.1524)
				(type default)
			)
			(layer "F.SilkS")
		)
		(fp_line
			(start -5.249926 -3.979926)
			(end -5.249926 -1.2446)
			(stroke
				(width 0.1524)
				(type default)
			)
			(layer "F.SilkS")
		)
		(fp_line
			(start 5.249926 5.249926)
			(end 5.249926 -5.249926)
			(stroke
				(width 0.1)
				(type default)
			)
			(layer "F.Fab")
		)
		(fp_line
			(start 5.249926 -5.249926)
			(end -5.249926 -5.249926)
			(stroke
				(width 0.1)
				(type default)
			)
			(layer "F.Fab")
		)
		(fp_line
			(start -5.249926 5.249926)
			(end 5.249926 5.249926)
			(stroke
				(width 0.1)
				(type default)
			)
			(layer "F.Fab")
		)
		(fp_line
			(start -5.249926 -5.249926)
			(end -5.249926 5.249926)
			(stroke
				(width 0.1)
				(type default)
			)
			(layer "F.Fab")
		)
		(pad "1" smd rect
			(at -4.45008 0 270)
			(size 2.2098 4.4196)
			(layers "F.Cu" "F.Mask" "F.Paste")
			(net "P52V_FAN_0")
		)
		(pad "2" smd rect
			(at 4.45008 0 270)
			(size 2.2098 4.4196)
			(layers "F.Cu" "F.Mask" "F.Paste")
			(net "GND")
		)
	)
	(footprint ""
		(layer "F.Cu")
		(at 10.287 -179.959)
		(property "Reference" "U7"
			(at 0.889 4.72567 0)
			(unlocked yes)
			(layer "F.SilkS")
			(effects
				(font
					(size 0.7874 0.5842)
					(thickness 0.1524)
				)
				(justify left)
			)
		)
		(property "Value" ""
			(at 0 0 0)
			(layer "F.Fab")
			(effects
				(font
					(size 1.27 1.27)
				)
			)
		)
		(duplicate_pad_numbers_are_jumpers no)
		(fp_line
			(start -2.0066 -3.9624)
			(end -0.5842 -3.9624)
			(stroke
				(width 0.1524)
				(type default)
			)
			(layer "F.SilkS")
		)
		(fp_line
			(start -2.0066 3.9624)
			(end -2.0066 -3.9624)
			(stroke
				(width 0.1524)
				(type default)
			)
			(layer "F.SilkS")
		)
		(fp_line
			(start -0.5842 -3.9624)
			(end 0 -3.3782)
			(stroke
				(width 0.1524)
				(type default)
			)
			(layer "F.SilkS")
		)
		(fp_line
			(start 0 -3.3782)
			(end 0.5842 -3.9624)
			(stroke
				(width 0.1524)
				(type default)
			)
			(layer "F.SilkS")
		)
		(fp_line
			(start 0.5842 -3.9624)
			(end 2.0066 -3.9624)
			(stroke
				(width 0.1524)
				(type default)
			)
			(layer "F.SilkS")
		)
		(fp_line
			(start 2.0066 -3.9624)
			(end 2.0066 3.9624)
			(stroke
				(width 0.1524)
				(type default)
			)
			(layer "F.SilkS")
		)
		(fp_line
			(start 2.0066 3.9624)
			(end -2.0066 3.9624)
			(stroke
				(width 0.1524)
				(type default)
			)
			(layer "F.SilkS")
		)
		(fp_poly
			(pts
				(xy -3.8862 -3.570986) (xy -4.6482 -3.189986) (xy -4.6482 -3.951986)
			)
			(stroke
				(width 0)
				(type default)
			)
			(fill yes)
			(layer "F.SilkS")
		)
		(fp_line
			(start -3.724402 -3.80365)
			(end -3.724402 3.80365)
			(stroke
				(width 0.1)
				(type default)
			)
			(layer "F.Fab")
		)
		(fp_line
			(start -3.724402 3.80365)
			(end -2.2479 3.80365)
			(stroke
				(width 0.1)
				(type default)
			)
			(layer "F.Fab")
		)
		(fp_line
			(start -3.7211 -3.34645)
			(end -3.7211 -3.80365)
			(stroke
				(width 0.1)
				(type default)
			)
			(layer "F.Fab")
		)
		(fp_line
			(start -2.2479 -3.974846)
			(end -2.2479 -3.80365)
			(stroke
				(width 0.1)
				(type default)
			)
			(layer "F.Fab")
		)
		(fp_line
			(start -2.2479 -3.80365)
			(end -3.724402 -3.80365)
			(stroke
				(width 0.1)
				(type default)
			)
			(layer "F.Fab")
		)
		(fp_line
			(start -2.2479 3.80365)
			(end -2.2479 3.9624)
			(stroke
				(width 0.1)
				(type default)
			)
			(layer "F.Fab")
		)
		(fp_line
			(start -2.2479 3.9624)
			(end 2.2479 3.9624)
			(stroke
				(width 0.1)
				(type default)
			)
			(layer "F.Fab")
		)
		(fp_line
			(start 2.2479 -3.974846)
			(end -2.2479 -3.974846)
			(stroke
				(width 0.1)
				(type default)
			)
			(layer "F.Fab")
		)
		(fp_line
			(start 2.2479 -3.80365)
			(end 2.2479 -3.974846)
			(stroke
				(width 0.1)
				(type default)
			)
			(layer "F.Fab")
		)
		(fp_line
			(start 2.2479 3.80365)
			(end 3.7211 3.80365)
			(stroke
				(width 0.1)
				(type default)
			)
			(layer "F.Fab")
		)
		(fp_line
			(start 2.2479 3.9624)
			(end 2.2479 3.80365)
			(stroke
				(width 0.1)
				(type default)
			)
			(layer "F.Fab")
		)
		(fp_line
			(start 3.7211 -3.80365)
			(end 2.2479 -3.80365)
			(stroke
				(width 0.1)
				(type default)
			)
			(layer "F.Fab")
		)
		(fp_line
			(start 3.7211 3.80365)
			(end 3.7211 -3.80365)
			(stroke
				(width 0.1)
				(type default)
			)
			(layer "F.Fab")
		)
		(fp_poly
			(pts
				(xy -3.8862 -3.570986) (xy -4.6482 -3.189986) (xy -4.6482 -3.951986)
			)
			(stroke
				(width 0)
				(type default)
			)
			(fill yes)
			(layer "F.Fab")
		)
		(pad "1" smd rect
			(at -2.921 -3.57505 270)
			(size 0.3556 1.4986)
			(layers "F.Cu" "F.Mask" "F.Paste")
			(net "PU_U7_PIN2")
		)
		(pad "2" smd rect
			(at -2.921 -2.925064 270)
			(size 0.3556 1.4986)
			(layers "F.Cu" "F.Mask" "F.Paste")
			(net "PCA9555_MB0_A1")
		)
		(pad "3" smd rect
			(at -2.921 -2.275078 270)
			(size 0.3556 1.4986)
			(layers "F.Cu" "F.Mask" "F.Paste")
			(net "PCA9555_MB0_A2")
		)
		(pad "4" smd rect
			(at -2.921 -1.625092 270)
			(size 0.3556 1.4986)
			(layers "F.Cu" "F.Mask" "F.Paste")
			(net "FAN_0_PRSNT_BUF_N")
		)
		(pad "5" smd rect
			(at -2.921 -0.975106 270)
			(size 0.3556 1.4986)
			(layers "F.Cu" "F.Mask" "F.Paste")
			(net "FAN_1_PRSNT_BUF_N")
		)
		(pad "6" smd rect
			(at -2.921 -0.32512 270)
			(size 0.3556 1.4986)
			(layers "F.Cu" "F.Mask" "F.Paste")
			(net "FAN_2_PRSNT_BUF_N")
		)
		(pad "7" smd rect
			(at -2.921 0.32512 270)
			(size 0.3556 1.4986)
			(layers "F.Cu" "F.Mask" "F.Paste")
			(net "FAN_3_PRSNT_BUF_N")
		)
		(pad "8" smd rect
			(at -2.921 0.975106 270)
			(size 0.3556 1.4986)
			(layers "F.Cu" "F.Mask" "F.Paste")
			(net "FAN_4_PRSNT_BUF_N")
		)
		(pad "9" smd rect
			(at -2.921 1.625092 270)
			(size 0.3556 1.4986)
			(layers "F.Cu" "F.Mask" "F.Paste")
			(net "FAN_5_PRSNT_BUF_N")
		)
		(pad "10" smd rect
			(at -2.921 2.275078 270)
			(size 0.3556 1.4986)
			(layers "F.Cu" "F.Mask" "F.Paste")
			(net "FAN_6_PRSNT_BUF_N")
		)
		(pad "11" smd rect
			(at -2.921 2.925064 270)
			(size 0.3556 1.4986)
			(layers "F.Cu" "F.Mask" "F.Paste")
			(net "FAN_7_PRSNT_BUF_N")
		)
		(pad "12" smd rect
			(at -2.921 3.57505 270)
			(size 0.3556 1.4986)
			(layers "F.Cu" "F.Mask" "F.Paste")
			(net "GND")
		)
		(pad "13" smd rect
			(at 2.921 3.57505 270)
			(size 0.3556 1.4986)
			(layers "F.Cu" "F.Mask" "F.Paste")
			(net "FM_BOARD_SKU_ID0")
		)
		(pad "14" smd rect
			(at 2.921 2.925064 270)
			(size 0.3556 1.4986)
			(layers "F.Cu" "F.Mask" "F.Paste")
			(net "FM_BOARD_SKU_ID1")
		)
		(pad "15" smd rect
			(at 2.921 2.275078 270)
			(size 0.3556 1.4986)
			(layers "F.Cu" "F.Mask" "F.Paste")
			(net "FM_BOARD_SKU_ID2")
		)
		(pad "16" smd rect
			(at 2.921 1.625092 270)
			(size 0.3556 1.4986)
			(layers "F.Cu" "F.Mask" "F.Paste")
			(net "TP_U7_PIN16")
		)
		(pad "17" smd rect
			(at 2.921 0.975106 270)
			(size 0.3556 1.4986)
			(layers "F.Cu" "F.Mask" "F.Paste")
			(net "FM_BOARD_ID0")
		)
		(pad "18" smd rect
			(at 2.921 0.32512 270)
			(size 0.3556 1.4986)
			(layers "F.Cu" "F.Mask" "F.Paste")
			(net "FM_BOARD_ID1")
		)
		(pad "19" smd rect
			(at 2.921 -0.32512 270)
			(size 0.3556 1.4986)
			(layers "F.Cu" "F.Mask" "F.Paste")
			(net "FM_BOARD_ID2")
		)
		(pad "20" smd rect
			(at 2.921 -0.975106 270)
			(size 0.3556 1.4986)
			(layers "F.Cu" "F.Mask" "F.Paste")
			(net "TP_U7_PIN20")
		)
		(pad "21" smd rect
			(at 2.921 -1.625092 270)
			(size 0.3556 1.4986)
			(layers "F.Cu" "F.Mask" "F.Paste")
			(net "PCA9555_MB0_A0")
		)
		(pad "22" smd rect
			(at 2.921 -2.275078 270)
			(size 0.3556 1.4986)
			(layers "F.Cu" "F.Mask" "F.Paste")
			(net "SMB_PDBV_FAN_R_IOX_SCL")
		)
		(pad "23" smd rect
			(at 2.921 -2.925064 270)
			(size 0.3556 1.4986)
			(layers "F.Cu" "F.Mask" "F.Paste")
			(net "SMB_PDBV_FAN_R_IOX_SDA")
		)
		(pad "24" smd rect
			(at 2.921 -3.57505 270)
			(size 0.3556 1.4986)
			(layers "F.Cu" "F.Mask" "F.Paste")
			(net "P3V3_AUX")
		)
	)
	(footprint ""
		(layer "F.Cu")
		(at 14.478 -197.739 180)
		(property "Reference" "D254"
			(at 4.2926 0.05715 0)
			(unlocked yes)
			(layer "F.SilkS")
			(effects
				(font
					(size 0.635 0.4064)
					(thickness 0.1524)
				)
				(justify left)
			)
		)
		(property "Value" ""
			(at 0 0 180)
			(layer "F.Fab")
			(effects
				(font
					(size 1.27 1.27)
				)
			)
		)
		(duplicate_pad_numbers_are_jumpers no)
		(fp_line
			(start 0.94488 0.450088)
			(end 0.94488 -0.450088)
			(stroke
				(width 0.1524)
				(type default)
			)
			(layer "F.SilkS")
		)
		(fp_line
			(start 0.94488 -0.450088)
			(end -0.854964 -0.450088)
			(stroke
				(width 0.1524)
				(type default)
			)
			(layer "F.SilkS")
		)
		(fp_line
			(start 0.870458 -0.2794)
			(end 0.845058 0.4064)
			(stroke
				(width 0.1524)
				(type default)
			)
			(layer "F.SilkS")
		)
		(fp_line
			(start 0.845058 0.4064)
			(end 0.845058 -0.381)
			(stroke
				(width 0.1524)
				(type default)
			)
			(layer "F.SilkS")
		)
		(fp_line
			(start -0.854964 0.450088)
			(end 0.925068 0.450088)
			(stroke
				(width 0.1524)
				(type default)
			)
			(layer "F.SilkS")
		)
		(fp_line
			(start -0.854964 -0.450088)
			(end -0.854964 0.450088)
			(stroke
				(width 0.1524)
				(type default)
			)
			(layer "F.SilkS")
		)
		(fp_line
			(start 0.54991 0.350012)
			(end 0.54991 -0.350012)
			(stroke
				(width 0.1)
				(type default)
			)
			(layer "F.Fab")
		)
		(fp_line
			(start 0.54991 -0.350012)
			(end -0.54991 -0.350012)
			(stroke
				(width 0.1)
				(type default)
			)
			(layer "F.Fab")
		)
		(fp_line
			(start -0.54991 0.350012)
			(end 0.54991 0.350012)
			(stroke
				(width 0.1)
				(type default)
			)
			(layer "F.Fab")
		)
		(fp_line
			(start -0.54991 -0.350012)
			(end -0.54991 0.350012)
			(stroke
				(width 0.1)
				(type default)
			)
			(layer "F.Fab")
		)
		(fp_text user "-"
			(at 2.296922 0.155194 0)
			(unlocked yes)
			(layer "F.SilkS")
			(effects
				(font
					(size 1.905 1.4224)
					(thickness 0.1524)
				)
				(justify left)
			)
		)
		(fp_text user "+"
			(at -0.3048 0.93345 0)
			(unlocked yes)
			(layer "F.SilkS")
			(effects
				(font
					(size 1.905 1.4224)
					(thickness 0.1524)
				)
				(justify left)
			)
		)
		(fp_text user "-"
			(at 2.48539 0.239014 0)
			(unlocked yes)
			(layer "F.Fab")
			(effects
				(font
					(size 1.905 1.4224)
					(thickness 0.1524)
				)
				(justify left)
			)
		)
		(fp_text user "+"
			(at -0.808228 0.239014 0)
			(unlocked yes)
			(layer "F.Fab")
			(effects
				(font
					(size 1.905 1.4224)
					(thickness 0.1524)
				)
				(justify left)
			)
		)
		(pad "A" smd rect
			(at -0.424942 0 180)
			(size 0.5588 0.6096)
			(layers "F.Cu" "F.Mask" "F.Paste")
			(net "GND")
		)
		(pad "C" smd rect
			(at 0.424942 0)
			(size 0.5588 0.6096)
			(layers "F.Cu" "F.Mask" "F.Paste")
			(net "FAN_6_TACH_IL_D")
		)
	)
	(footprint ""
		(layer "F.Cu")
		(at 18.415 -190.881 180)
		(property "Reference" "C93"
			(at 0 0 180)
			(layer "F.SilkS")
			(hide yes)
			(effects
				(font
					(size 1.27 1.27)
				)
			)
		)
		(property "Value" ""
			(at 0 0 180)
			(layer "F.Fab")
			(effects
				(font
					(size 1.27 1.27)
				)
			)
		)
		(duplicate_pad_numbers_are_jumpers no)
		(fp_line
			(start 0.7874 0.4064)
			(end -0.7874 0.4064)
			(stroke
				(width 0.1524)
				(type default)
			)
			(layer "F.SilkS")
		)
		(fp_line
			(start 0.7874 -0.4064)
			(end 0.7874 0.4064)
			(stroke
				(width 0.1524)
				(type default)
			)
			(layer "F.SilkS")
		)
		(fp_line
			(start -0.7874 0.4064)
			(end -0.7874 -0.4064)
			(stroke
				(width 0.1524)
				(type default)
			)
			(layer "F.SilkS")
		)
		(fp_line
			(start -0.7874 -0.4064)
			(end 0.7874 -0.4064)
			(stroke
				(width 0.1524)
				(type default)
			)
			(layer "F.SilkS")
		)
		(fp_line
			(start 0.67945 0.3048)
			(end 0.120396 0.3048)
			(stroke
				(width 0.1)
				(type default)
			)
			(layer "F.Fab")
		)
		(fp_line
			(start 0.67945 -0.3048)
			(end 0.67945 0.3048)
			(stroke
				(width 0.1)
				(type default)
			)
			(layer "F.Fab")
		)
		(fp_line
			(start 0.12065 -0.2794)
			(end 0.12065 -0.3048)
			(stroke
				(width 0.1)
				(type default)
			)
			(layer "F.Fab")
		)
		(fp_line
			(start 0.12065 -0.3048)
			(end 0.67945 -0.3048)
			(stroke
				(width 0.1)
				(type default)
			)
			(layer "F.Fab")
		)
		(fp_line
			(start 0.120396 0.3048)
			(end 0.120396 0.2794)
			(stroke
				(width 0.1)
				(type default)
			)
			(layer "F.Fab")
		)
		(fp_line
			(start 0.120396 0.2794)
			(end -0.12065 0.2794)
			(stroke
				(width 0.1)
				(type default)
			)
			(layer "F.Fab")
		)
		(fp_line
			(start -0.12065 0.3048)
			(end -0.67945 0.3048)
			(stroke
				(width 0.1)
				(type default)
			)
			(layer "F.Fab")
		)
		(fp_line
			(start -0.12065 0.2794)
			(end -0.12065 0.3048)
			(stroke
				(width 0.1)
				(type default)
			)
			(layer "F.Fab")
		)
		(fp_line
			(start -0.12065 -0.2794)
			(end 0.12065 -0.2794)
			(stroke
				(width 0.1)
				(type default)
			)
			(layer "F.Fab")
		)
		(fp_line
			(start -0.12065 -0.305054)
			(end -0.12065 -0.2794)
			(stroke
				(width 0.1)
				(type default)
			)
			(layer "F.Fab")
		)
		(fp_line
			(start -0.67945 0.3048)
			(end -0.67945 -0.305054)
			(stroke
				(width 0.1)
				(type default)
			)
			(layer "F.Fab")
		)
		(fp_line
			(start -0.67945 -0.305054)
			(end -0.12065 -0.305054)
			(stroke
				(width 0.1)
				(type default)
			)
			(layer "F.Fab")
		)
		(pad "1" smd circle
			(at -0.40005 0 180)
			(size 0 0)
			(layers "F.Cu" "F.Mask" "F.Paste")
			(net "GND")
		)
		(pad "2" smd circle
			(at 0.40005 0 180)
			(size 0 0)
			(layers "F.Cu" "F.Mask" "F.Paste")
			(net "P3V3_AUX")
		)
	)
	(footprint ""
		(layer "F.Cu")
		(at 19.431 -294.386 -90)
		(property "Reference" "R5379"
			(at 0 0 270)
			(layer "F.SilkS")
			(hide yes)
			(effects
				(font
					(size 1.27 1.27)
				)
			)
		)
		(property "Value" ""
			(at 0 0 270)
			(layer "F.Fab")
			(effects
				(font
					(size 1.27 1.27)
				)
			)
		)
		(duplicate_pad_numbers_are_jumpers no)
		(fp_line
			(start -0.7874 0.4064)
			(end -0.7874 -0.4064)
			(stroke
				(width 0.1524)
				(type default)
			)
			(layer "F.SilkS")
		)
		(fp_line
			(start 0.7874 0.4064)
			(end -0.7874 0.4064)
			(stroke
				(width 0.1524)
				(type default)
			)
			(layer "F.SilkS")
		)
		(fp_line
			(start -0.7874 -0.4064)
			(end 0.7874 -0.4064)
			(stroke
				(width 0.1524)
				(type default)
			)
			(layer "F.SilkS")
		)
		(fp_line
			(start 0.7874 -0.4064)
			(end 0.7874 0.4064)
			(stroke
				(width 0.1524)
				(type default)
			)
			(layer "F.SilkS")
		)
		(fp_line
			(start -0.67945 0.3048)
			(end -0.67945 -0.305054)
			(stroke
				(width 0.1)
				(type default)
			)
			(layer "F.Fab")
		)
		(fp_line
			(start -0.12065 0.3048)
			(end -0.67945 0.3048)
			(stroke
				(width 0.1)
				(type default)
			)
			(layer "F.Fab")
		)
		(fp_line
			(start 0.120396 0.3048)
			(end 0.120396 0.2794)
			(stroke
				(width 0.1)
				(type default)
			)
			(layer "F.Fab")
		)
		(fp_line
			(start 0.67945 0.3048)
			(end 0.120396 0.3048)
			(stroke
				(width 0.1)
				(type default)
			)
			(layer "F.Fab")
		)
		(fp_line
			(start -0.12065 0.2794)
			(end -0.12065 0.3048)
			(stroke
				(width 0.1)
				(type default)
			)
			(layer "F.Fab")
		)
		(fp_line
			(start 0.120396 0.2794)
			(end -0.12065 0.2794)
			(stroke
				(width 0.1)
				(type default)
			)
			(layer "F.Fab")
		)
		(fp_line
			(start -0.12065 -0.2794)
			(end 0.12065 -0.2794)
			(stroke
				(width 0.1)
				(type default)
			)
			(layer "F.Fab")
		)
		(fp_line
			(start 0.12065 -0.2794)
			(end 0.12065 -0.3048)
			(stroke
				(width 0.1)
				(type default)
			)
			(layer "F.Fab")
		)
		(fp_line
			(start 0.12065 -0.3048)
			(end 0.67945 -0.3048)
			(stroke
				(width 0.1)
				(type default)
			)
			(layer "F.Fab")
		)
		(fp_line
			(start 0.67945 -0.3048)
			(end 0.67945 0.3048)
			(stroke
				(width 0.1)
				(type default)
			)
			(layer "F.Fab")
		)
		(fp_line
			(start -0.67945 -0.305054)
			(end -0.12065 -0.305054)
			(stroke
				(width 0.1)
				(type default)
			)
			(layer "F.Fab")
		)
		(fp_line
			(start -0.12065 -0.305054)
			(end -0.12065 -0.2794)
			(stroke
				(width 0.1)
				(type default)
			)
			(layer "F.Fab")
		)
		(pad "1" smd circle
			(at -0.40005 0 270)
			(size 0 0)
			(layers "F.Cu" "F.Mask" "F.Paste")
			(net "P3V3_AUX")
		)
		(pad "2" smd circle
			(at 0.40005 0 270)
			(size 0 0)
			(layers "F.Cu" "F.Mask" "F.Paste")
			(net "FAN_7_FAIL_R_LED")
		)
	)
)
